G04*
G04 #@! TF.GenerationSoftware,Altium Limited,Altium Designer,23.6.0 (18)*
G04*
G04 Layer_Color=8421504*
%FSLAX44Y44*%
%MOMM*%
G71*
G04*
G04 #@! TF.SameCoordinates,B62FFF2A-40BB-47C2-B022-6C0D6E2DF31E*
G04*
G04*
G04 #@! TF.FilePolarity,Positive*
G04*
G01*
G75*
%ADD22R,0.8000X0.8500*%
%ADD23R,0.9000X2.0000*%
%ADD24R,0.5969X0.8954*%
%ADD25R,0.8001X1.2065*%
%ADD26R,0.5500X0.6000*%
G04:AMPARAMS|DCode=27|XSize=1.164mm|YSize=0.3358mm|CornerRadius=0.1679mm|HoleSize=0mm|Usage=FLASHONLY|Rotation=90.000|XOffset=0mm|YOffset=0mm|HoleType=Round|Shape=RoundedRectangle|*
%AMROUNDEDRECTD27*
21,1,1.1640,0.0000,0,0,90.0*
21,1,0.8281,0.3358,0,0,90.0*
1,1,0.3358,0.0000,0.4141*
1,1,0.3358,0.0000,-0.4141*
1,1,0.3358,0.0000,-0.4141*
1,1,0.3358,0.0000,0.4141*
%
%ADD27ROUNDEDRECTD27*%
%ADD28R,0.3358X1.1640*%
%ADD29R,0.8000X0.8000*%
%ADD30R,0.5500X0.5500*%
%ADD31R,0.5500X0.5500*%
%ADD32R,0.5153X0.4725*%
%ADD33R,0.3500X1.4500*%
%ADD34R,0.4500X0.5000*%
%ADD35R,1.1546X1.7062*%
%ADD36R,1.2700X0.5588*%
%ADD37R,0.6000X0.9000*%
%ADD38R,0.5000X0.6000*%
%ADD39R,0.8000X0.8000*%
%ADD40R,0.5000X0.5000*%
%ADD41R,0.5000X0.5000*%
%ADD42R,0.6000X0.5000*%
D22*
X34000Y383761D02*
D03*
D23*
X19001Y399001D02*
D03*
X48999Y398999D02*
D03*
D24*
X38989Y185364D02*
D03*
X49990Y185364D02*
D03*
X60989Y185364D02*
D03*
X71990Y185364D02*
D03*
X82990D02*
D03*
X112989Y185364D02*
D03*
X123990Y185364D02*
D03*
X134989Y185364D02*
D03*
X145989D02*
D03*
X156990Y185364D02*
D03*
X167989Y185364D02*
D03*
X178990Y185364D02*
D03*
X38989Y292632D02*
D03*
X49990Y292633D02*
D03*
X60989Y292632D02*
D03*
X71990Y292633D02*
D03*
X82990D02*
D03*
X112989Y292632D02*
D03*
X123990Y292633D02*
D03*
X134989Y292632D02*
D03*
X145989D02*
D03*
X156990Y292633D02*
D03*
X167989Y292632D02*
D03*
X178990Y292633D02*
D03*
D25*
X38989Y174950D02*
D03*
X49990Y174951D02*
D03*
X60989Y174950D02*
D03*
X71990Y174951D02*
D03*
X82990D02*
D03*
X112990Y174950D02*
D03*
X123990Y174951D02*
D03*
X134989Y174950D02*
D03*
X145989D02*
D03*
X156990Y174951D02*
D03*
X167989Y174950D02*
D03*
X178990Y174951D02*
D03*
X38989Y303046D02*
D03*
X49990Y303046D02*
D03*
X60989Y303046D02*
D03*
X71990Y303046D02*
D03*
X82990D02*
D03*
X112990Y303046D02*
D03*
X123990Y303046D02*
D03*
X134989Y303046D02*
D03*
X145989D02*
D03*
X156990Y303046D02*
D03*
X167989Y303046D02*
D03*
X178990Y303046D02*
D03*
D26*
X31000Y137250D02*
D03*
Y128750D02*
D03*
X42000Y137250D02*
D03*
Y128750D02*
D03*
X38000Y73250D02*
D03*
Y64750D02*
D03*
X80000Y73250D02*
D03*
Y64750D02*
D03*
D27*
X63000Y147701D02*
D03*
X69500Y132299D02*
D03*
D28*
X56500D02*
D03*
D29*
X85384Y138540D02*
D03*
Y153540D02*
D03*
D30*
X85523Y118856D02*
D03*
Y127856D02*
D03*
D31*
X124500Y106000D02*
D03*
X115500D02*
D03*
D32*
X39214Y360000D02*
D03*
X46786D02*
D03*
D33*
X17500Y12750D02*
D03*
X22500D02*
D03*
X27500D02*
D03*
X32500D02*
D03*
X37500D02*
D03*
X42500D02*
D03*
X47500D02*
D03*
X52500D02*
D03*
X57500D02*
D03*
X62500D02*
D03*
X67500D02*
D03*
X72500D02*
D03*
X77500D02*
D03*
X82500D02*
D03*
X87500D02*
D03*
X92500D02*
D03*
X97500D02*
D03*
X102500D02*
D03*
X107500D02*
D03*
X112500D02*
D03*
X117500D02*
D03*
X122500D02*
D03*
X127500D02*
D03*
X132500D02*
D03*
X137500D02*
D03*
X142500D02*
D03*
X147500D02*
D03*
X152500D02*
D03*
X187500D02*
D03*
X192500D02*
D03*
X197500D02*
D03*
X202500D02*
D03*
X182500D02*
D03*
X177500D02*
D03*
D34*
X102000Y136750D02*
D03*
Y129250D02*
D03*
X117000Y136750D02*
D03*
Y129250D02*
D03*
D35*
X185758Y96000D02*
D03*
X160242D02*
D03*
X185758Y119000D02*
D03*
X160242D02*
D03*
D36*
X121304Y346850D02*
D03*
Y365150D02*
D03*
X102000Y356000D02*
D03*
D37*
X59500Y344000D02*
D03*
X74500D02*
D03*
D38*
X170000Y340000D02*
D03*
X160000D02*
D03*
X95000Y324000D02*
D03*
X105000D02*
D03*
X160000Y360000D02*
D03*
X170000D02*
D03*
D39*
X127500Y88000D02*
D03*
X112500D02*
D03*
D40*
X70000Y360000D02*
D03*
X60000D02*
D03*
X179000Y160000D02*
D03*
X169000D02*
D03*
X179000Y148000D02*
D03*
X169000D02*
D03*
X179000Y136000D02*
D03*
X169000D02*
D03*
D41*
X39000Y348000D02*
D03*
Y338000D02*
D03*
D42*
X66000Y64000D02*
D03*
Y74000D02*
D03*
X52000Y64000D02*
D03*
Y74000D02*
D03*
X190000Y335000D02*
D03*
Y345000D02*
D03*
X141000Y361000D02*
D03*
Y351000D02*
D03*
M02*
